(kicad_pcb
	(version 20260206)
	(generator "pcbnew")
	(generator_version "10.0")
	(general
		(thickness 1.6)
		(legacy_teardrops no)
	)
	(paper "A4")
	(title_block
		(title "v1-tray-backplane — T6M_tray_BP_c_1023_1120.brd")
		(comment 1 "Open CloudServer (Microsoft) / footprints 1-8 of 170")
	)
	(layers
		(0 "F.Cu" signal "TOP")
		(4 "In1.Cu" signal "GND")
		(6 "In2.Cu" signal "IN1")
		(8 "In3.Cu" signal "VCC")
		(10 "In4.Cu" signal "VCC1")
		(12 "In5.Cu" signal "IN2")
		(14 "In6.Cu" signal "GND1")
		(2 "B.Cu" signal "BOTTOM")
		(9 "F.Adhes" user "F.Adhesive")
		(11 "B.Adhes" user "B.Adhesive")
		(13 "F.Paste" user "Package Geometry/Pastemask Top")
		(15 "B.Paste" user "Package Geometry/Pastemask Bottom")
		(5 "F.SilkS" user "Ref Des/Silkscreen Top")
		(7 "B.SilkS" user "Ref Des/Silkscreen Bottom")
		(1 "F.Mask" user "Board Geometry/Soldermask Top")
		(3 "B.Mask" user "Board Geometry/Soldermask Bottom")
		(17 "Dwgs.User" user "User.Drawings")
		(19 "Cmts.User" user "User.Comments")
		(21 "Eco1.User" user "User.Eco1")
		(23 "Eco2.User" user "User.Eco2")
		(25 "Edge.Cuts" user "Board Geometry/Outline")
		(27 "Margin" user)
		(31 "F.CrtYd" user "Package Geometry/Place Bound Top")
		(29 "B.CrtYd" user "Package Geometry/Place Bound Bottom")
		(35 "F.Fab" user "Ref Des/Assembly Top")
		(33 "B.Fab" user "Ref Des/Assembly Bottom")
	)
	(footprint ""
		(layer "F.Cu")
		(at 3.578352 -23.357332 180)
		(property "Reference" "JP4"
			(at 2.610104 -5.567934 0)
			(unlocked yes)
			(layer "F.SilkS")
			(effects
				(font
					(size 0.7874 0.5842)
					(thickness 0.1524)
				)
				(justify left)
			)
		)
		(property "Value" ""
			(at 0 0 180)
			(layer "F.Fab")
			(effects
				(font
					(size 1.27 1.27)
				)
			)
		)
		(duplicate_pad_numbers_are_jumpers no)
		(fp_line
			(start 2.54 1.27)
			(end -2.54 1.27)
			(stroke
				(width 0.1524)
				(type default)
			)
			(layer "F.SilkS")
		)
		(fp_line
			(start 2.54 -1.27)
			(end 2.54 1.27)
			(stroke
				(width 0.1524)
				(type default)
			)
			(layer "F.SilkS")
		)
		(fp_line
			(start -2.54 1.27)
			(end -2.54 -1.27)
			(stroke
				(width 0.1524)
				(type default)
			)
			(layer "F.SilkS")
		)
		(fp_line
			(start -2.54 -1.27)
			(end 2.54 -1.27)
			(stroke
				(width 0.1524)
				(type default)
			)
			(layer "F.SilkS")
		)
		(fp_poly
			(pts
				(xy -2.80035 0.82677) (xy -4.147566 1.347724) (xy -3.285236 2.2098)
			)
			(stroke
				(width 0)
				(type default)
			)
			(fill yes)
			(layer "F.SilkS")
		)
		(fp_poly
			(pts
				(xy -2.1082 -0.8382) (xy -2.1082 0.8382) (xy 2.1082 0.8382) (xy 2.1082 -0.8382)
			)
			(stroke
				(width 0)
				(type default)
			)
			(fill no)
			(layer "B.CrtYd")
		)
		(fp_rect
			(start -2.54 1.27)
			(end 2.54 -1.27)
			(stroke
				(width 0)
				(type default)
			)
			(fill no)
			(layer "F.CrtYd")
		)
		(fp_line
			(start 2.54 1.27)
			(end -2.54 1.27)
			(stroke
				(width 0.1)
				(type default)
			)
			(layer "F.Fab")
		)
		(fp_line
			(start 2.54 -1.27)
			(end 2.54 1.27)
			(stroke
				(width 0.1)
				(type default)
			)
			(layer "F.Fab")
		)
		(fp_line
			(start -2.54 1.27)
			(end -2.54 -1.27)
			(stroke
				(width 0.1)
				(type default)
			)
			(layer "F.Fab")
		)
		(fp_line
			(start -2.54 -1.27)
			(end 2.54 -1.27)
			(stroke
				(width 0.1)
				(type default)
			)
			(layer "F.Fab")
		)
		(fp_text user "2"
			(at 2.838704 2.026666 0)
			(unlocked yes)
			(layer "F.SilkS")
			(effects
				(font
					(size 0.7874 0.5842)
					(thickness 0.1524)
				)
				(justify left)
			)
		)
		(fp_text user "1"
			(at -2.698496 -0.843534 0)
			(unlocked yes)
			(layer "F.SilkS")
			(effects
				(font
					(size 0.7874 0.5842)
					(thickness 0.1524)
				)
				(justify left)
			)
		)
		(fp_text user "2"
			(at 2.381504 -0.132334 0)
			(unlocked yes)
			(layer "B.SilkS")
			(effects
				(font
					(size 0.7874 0.5842)
					(thickness 0.1524)
				)
				(justify left mirror)
			)
		)
		(fp_text user "1"
			(at -2.952496 -0.081534 0)
			(unlocked yes)
			(layer "B.SilkS")
			(effects
				(font
					(size 0.7874 0.5842)
					(thickness 0.1524)
				)
				(justify left mirror)
			)
		)
		(pad "1" thru_hole rect
			(at -1.27 0 180)
			(size 1.6764 1.6764)
			(drill 1.1684)
			(layers "*.Cu" "*.Mask")
			(remove_unused_layers no)
			(net "NODE1_EN")
			(clearance 0)
			(padstack
				(mode front_inner_back)
				(layer "Inner"
					(shape circle)
					(size 1.6764 1.6764)
					(clearance 0)
				)
				(layer "B.Cu"
					(shape rect)
					(size 1.6764 1.6764)
					(clearance 0)
				)
			)
		)
		(pad "2" thru_hole circle
			(at 1.27 0 180)
			(size 1.6764 1.6764)
			(drill 1.1684)
			(layers "*.Cu" "*.Mask")
			(remove_unused_layers no)
			(net "N39391900")
			(clearance 0)
		)
	)
	(footprint ""
		(layer "F.Cu")
		(at 128.229868 -21.750782 90)
		(property "Reference" "R58"
			(at -6.1722 -60.493148 90)
			(unlocked yes)
			(layer "F.SilkS")
			(effects
				(font
					(size 0.7874 0.5842)
					(thickness 0.1524)
				)
				(justify left)
			)
		)
		(property "Value" ""
			(at 0 0 90)
			(layer "F.Fab")
			(effects
				(font
					(size 1.27 1.27)
				)
			)
		)
		(duplicate_pad_numbers_are_jumpers no)
		(fp_line
			(start 0.7874 -0.4064)
			(end 0.7874 0.4064)
			(stroke
				(width 0.1524)
				(type default)
			)
			(layer "F.SilkS")
		)
		(fp_line
			(start -0.7874 -0.4064)
			(end 0.7874 -0.4064)
			(stroke
				(width 0.1524)
				(type default)
			)
			(layer "F.SilkS")
		)
		(fp_line
			(start 0.7874 0.4064)
			(end -0.7874 0.4064)
			(stroke
				(width 0.1524)
				(type default)
			)
			(layer "F.SilkS")
		)
		(fp_line
			(start -0.7874 0.4064)
			(end -0.7874 -0.4064)
			(stroke
				(width 0.1524)
				(type default)
			)
			(layer "F.SilkS")
		)
		(fp_poly
			(pts
				(xy -0.508 0.2794) (xy -0.508 0.2286) (xy -0.635 0.2286) (xy -0.635 -0.254) (xy -0.5334 -0.254)
				(xy -0.5334 -0.2794) (xy 0.5334 -0.2794) (xy 0.5334 -0.254) (xy 0.635 -0.254) (xy 0.635 0.254) (xy 0.5334 0.254)
				(xy 0.5334 0.2794)
			)
			(stroke
				(width 0)
				(type default)
			)
			(fill no)
			(layer "F.CrtYd")
		)
		(pad "1" smd rect
			(at 0.40005 0 90)
			(size 0.4572 0.508)
			(layers "F.Cu" "F.Mask" "F.Paste")
			(net "GND")
		)
		(pad "2" smd rect
			(at -0.40005 0 90)
			(size 0.4572 0.508)
			(layers "F.Cu" "F.Mask" "F.Paste")
			(net "SFP1_PRESENT_N")
		)
	)
	(footprint ""
		(layer "F.Cu")
		(at 312.248296 -23.367746 -90)
		(property "Reference" "C12"
			(at -1.397508 5.66674 90)
			(unlocked yes)
			(layer "F.SilkS")
			(effects
				(font
					(size 0.7874 0.5842)
					(thickness 0.1524)
				)
				(justify left)
			)
		)
		(property "Value" ""
			(at 0 0 270)
			(layer "F.Fab")
			(effects
				(font
					(size 1.27 1.27)
				)
			)
		)
		(duplicate_pad_numbers_are_jumpers no)
		(fp_line
			(start -0.7874 0.4064)
			(end -0.7874 -0.4064)
			(stroke
				(width 0.1524)
				(type default)
			)
			(layer "F.SilkS")
		)
		(fp_line
			(start 0.7874 0.4064)
			(end -0.7874 0.4064)
			(stroke
				(width 0.1524)
				(type default)
			)
			(layer "F.SilkS")
		)
		(fp_line
			(start 0 0.381)
			(end 0 -0.381)
			(stroke
				(width 0.1524)
				(type default)
			)
			(layer "F.SilkS")
		)
		(fp_line
			(start -0.7874 -0.4064)
			(end 0.7874 -0.4064)
			(stroke
				(width 0.1524)
				(type default)
			)
			(layer "F.SilkS")
		)
		(fp_line
			(start 0.7874 -0.4064)
			(end 0.7874 0.4064)
			(stroke
				(width 0.1524)
				(type default)
			)
			(layer "F.SilkS")
		)
		(fp_poly
			(pts
				(xy -0.5334 0.254) (xy -0.635 0.254) (xy -0.635 0.2286) (xy -0.635 -0.254) (xy -0.5334 -0.254) (xy -0.5334 -0.2794)
				(xy 0.5334 -0.2794) (xy 0.5334 -0.254) (xy 0.635 -0.254) (xy 0.635 0.254) (xy 0.5334 0.254) (xy 0.5334 0.2794)
				(xy -0.508 0.2794) (xy -0.5334 0.2794)
			)
			(stroke
				(width 0)
				(type default)
			)
			(fill no)
			(layer "F.CrtYd")
		)
		(pad "1" smd rect
			(at 0.40005 0 270)
			(size 0.4572 0.508)
			(layers "F.Cu" "F.Mask" "F.Paste")
			(net "P12V")
		)
		(pad "2" smd rect
			(at -0.40005 0 270)
			(size 0.4572 0.508)
			(layers "F.Cu" "F.Mask" "F.Paste")
			(net "GND")
		)
	)
	(footprint ""
		(layer "F.Cu")
		(at 349.594932 -21.561552 90)
		(property "Reference" "R71"
			(at 3.449066 -58.003948 90)
			(unlocked yes)
			(layer "F.SilkS")
			(effects
				(font
					(size 0.7874 0.5842)
					(thickness 0.1524)
				)
				(justify left)
			)
		)
		(property "Value" ""
			(at 0 0 90)
			(layer "F.Fab")
			(effects
				(font
					(size 1.27 1.27)
				)
			)
		)
		(duplicate_pad_numbers_are_jumpers no)
		(fp_line
			(start 0.7874 -0.4064)
			(end 0.7874 0.4064)
			(stroke
				(width 0.1524)
				(type default)
			)
			(layer "F.SilkS")
		)
		(fp_line
			(start -0.7874 -0.4064)
			(end 0.7874 -0.4064)
			(stroke
				(width 0.1524)
				(type default)
			)
			(layer "F.SilkS")
		)
		(fp_line
			(start 0.7874 0.4064)
			(end -0.7874 0.4064)
			(stroke
				(width 0.1524)
				(type default)
			)
			(layer "F.SilkS")
		)
		(fp_line
			(start -0.7874 0.4064)
			(end -0.7874 -0.4064)
			(stroke
				(width 0.1524)
				(type default)
			)
			(layer "F.SilkS")
		)
		(fp_poly
			(pts
				(xy -0.508 0.2794) (xy -0.508 0.2286) (xy -0.635 0.2286) (xy -0.635 -0.254) (xy -0.5334 -0.254)
				(xy -0.5334 -0.2794) (xy 0.5334 -0.2794) (xy 0.5334 -0.254) (xy 0.635 -0.254) (xy 0.635 0.254) (xy 0.5334 0.254)
				(xy 0.5334 0.2794)
			)
			(stroke
				(width 0)
				(type default)
			)
			(fill no)
			(layer "F.CrtYd")
		)
		(pad "1" smd rect
			(at 0.40005 0 90)
			(size 0.4572 0.508)
			(layers "F.Cu" "F.Mask" "F.Paste")
			(net "GND")
		)
		(pad "2" smd rect
			(at -0.40005 0 90)
			(size 0.4572 0.508)
			(layers "F.Cu" "F.Mask" "F.Paste")
			(net "SFP3_PRESENT_N")
		)
	)
	(footprint ""
		(layer "F.Cu")
		(at 340.261448 -21.147532 180)
		(property "Reference" "R73"
			(at 58.045096 4.355084 0)
			(unlocked yes)
			(layer "F.SilkS")
			(effects
				(font
					(size 0.7874 0.5842)
					(thickness 0.1524)
				)
				(justify left)
			)
		)
		(property "Value" ""
			(at 0 0 180)
			(layer "F.Fab")
			(effects
				(font
					(size 1.27 1.27)
				)
			)
		)
		(duplicate_pad_numbers_are_jumpers no)
		(fp_line
			(start 0.7874 0.4064)
			(end -0.7874 0.4064)
			(stroke
				(width 0.1524)
				(type default)
			)
			(layer "F.SilkS")
		)
		(fp_line
			(start 0.7874 -0.4064)
			(end 0.7874 0.4064)
			(stroke
				(width 0.1524)
				(type default)
			)
			(layer "F.SilkS")
		)
		(fp_line
			(start -0.7874 0.4064)
			(end -0.7874 -0.4064)
			(stroke
				(width 0.1524)
				(type default)
			)
			(layer "F.SilkS")
		)
		(fp_line
			(start -0.7874 -0.4064)
			(end 0.7874 -0.4064)
			(stroke
				(width 0.1524)
				(type default)
			)
			(layer "F.SilkS")
		)
		(fp_poly
			(pts
				(xy -0.508 0.2794) (xy -0.508 0.2286) (xy -0.635 0.2286) (xy -0.635 -0.254) (xy -0.5334 -0.254)
				(xy -0.5334 -0.2794) (xy 0.5334 -0.2794) (xy 0.5334 -0.254) (xy 0.635 -0.254) (xy 0.635 0.254) (xy 0.5334 0.254)
				(xy 0.5334 0.2794)
			)
			(stroke
				(width 0)
				(type default)
			)
			(fill no)
			(layer "F.CrtYd")
		)
		(pad "1" smd rect
			(at 0.40005 0 180)
			(size 0.4572 0.508)
			(layers "F.Cu" "F.Mask" "F.Paste")
			(net "ENET10G_4_MOD_DEF0")
		)
		(pad "2" smd rect
			(at -0.40005 0 180)
			(size 0.4572 0.508)
			(layers "F.Cu" "F.Mask" "F.Paste")
			(net "SFP4_PRESENT_N")
		)
	)
	(footprint ""
		(layer "F.Cu")
		(at 126.045468 -21.750782 -90)
		(property "Reference" "R39"
			(at 6.1722 60.395612 90)
			(unlocked yes)
			(layer "F.SilkS")
			(effects
				(font
					(size 0.7874 0.5842)
					(thickness 0.1524)
				)
				(justify left)
			)
		)
		(property "Value" ""
			(at 0 0 270)
			(layer "F.Fab")
			(effects
				(font
					(size 1.27 1.27)
				)
			)
		)
		(duplicate_pad_numbers_are_jumpers no)
		(fp_line
			(start -0.7874 0.4064)
			(end -0.7874 -0.4064)
			(stroke
				(width 0.1524)
				(type default)
			)
			(layer "F.SilkS")
		)
		(fp_line
			(start 0.7874 0.4064)
			(end -0.7874 0.4064)
			(stroke
				(width 0.1524)
				(type default)
			)
			(layer "F.SilkS")
		)
		(fp_line
			(start -0.7874 -0.4064)
			(end 0.7874 -0.4064)
			(stroke
				(width 0.1524)
				(type default)
			)
			(layer "F.SilkS")
		)
		(fp_line
			(start 0.7874 -0.4064)
			(end 0.7874 0.4064)
			(stroke
				(width 0.1524)
				(type default)
			)
			(layer "F.SilkS")
		)
		(fp_poly
			(pts
				(xy -0.508 0.2794) (xy -0.508 0.2286) (xy -0.635 0.2286) (xy -0.635 -0.254) (xy -0.5334 -0.254)
				(xy -0.5334 -0.2794) (xy 0.5334 -0.2794) (xy 0.5334 -0.254) (xy 0.635 -0.254) (xy 0.635 0.254) (xy 0.5334 0.254)
				(xy 0.5334 0.2794)
			)
			(stroke
				(width 0)
				(type default)
			)
			(fill no)
			(layer "F.CrtYd")
		)
		(pad "1" smd rect
			(at 0.40005 0 270)
			(size 0.4572 0.508)
			(layers "F.Cu" "F.Mask" "F.Paste")
			(net "SKU_PIN_BLAD1_1")
		)
		(pad "2" smd rect
			(at -0.40005 0 270)
			(size 0.4572 0.508)
			(layers "F.Cu" "F.Mask" "F.Paste")
			(net "P3V3_BLAD1")
		)
	)
	(footprint ""
		(layer "F.Cu")
		(at 154.89936 -24.165306 180)
		(property "Reference" "R3"
			(at -33.93948 -17.809464 0)
			(unlocked yes)
			(layer "F.SilkS")
			(effects
				(font
					(size 0.7874 0.5842)
					(thickness 0.1524)
				)
				(justify left)
			)
		)
		(property "Value" ""
			(at 0 0 180)
			(layer "F.Fab")
			(effects
				(font
					(size 1.27 1.27)
				)
			)
		)
		(duplicate_pad_numbers_are_jumpers no)
		(fp_line
			(start 0.7874 0.4064)
			(end -0.7874 0.4064)
			(stroke
				(width 0.1524)
				(type default)
			)
			(layer "F.SilkS")
		)
		(fp_line
			(start 0.7874 -0.4064)
			(end 0.7874 0.4064)
			(stroke
				(width 0.1524)
				(type default)
			)
			(layer "F.SilkS")
		)
		(fp_line
			(start -0.7874 0.4064)
			(end -0.7874 -0.4064)
			(stroke
				(width 0.1524)
				(type default)
			)
			(layer "F.SilkS")
		)
		(fp_line
			(start -0.7874 -0.4064)
			(end 0.7874 -0.4064)
			(stroke
				(width 0.1524)
				(type default)
			)
			(layer "F.SilkS")
		)
		(fp_poly
			(pts
				(xy -0.508 0.2794) (xy -0.508 0.2286) (xy -0.635 0.2286) (xy -0.635 -0.254) (xy -0.5334 -0.254)
				(xy -0.5334 -0.2794) (xy 0.5334 -0.2794) (xy 0.5334 -0.254) (xy 0.635 -0.254) (xy 0.635 0.254) (xy 0.5334 0.254)
				(xy 0.5334 0.2794)
			)
			(stroke
				(width 0)
				(type default)
			)
			(fill no)
			(layer "F.CrtYd")
		)
		(pad "1" smd rect
			(at 0.40005 0 180)
			(size 0.4572 0.508)
			(layers "F.Cu" "F.Mask" "F.Paste")
			(net "P3V3_BLAD1")
		)
		(pad "2" smd rect
			(at -0.40005 0 180)
			(size 0.4572 0.508)
			(layers "F.Cu" "F.Mask" "F.Paste")
			(net "ENET10G_1_TX_DIS")
		)
	)
	(footprint ""
		(layer "F.Cu")
		(at 92.305886 -37.875972 180)
		(property "Reference" "FS2"
			(at 2.846832 2.724404 0)
			(unlocked yes)
			(layer "F.SilkS")
			(effects
				(font
					(size 0.7874 0.5842)
					(thickness 0.1524)
				)
				(justify left)
			)
		)
		(property "Value" ""
			(at 0 0 180)
			(layer "F.Fab")
			(effects
				(font
					(size 1.27 1.27)
				)
			)
		)
		(duplicate_pad_numbers_are_jumpers no)
		(fp_line
			(start 3.550412 1.050036)
			(end -0.650494 1.050036)
			(stroke
				(width 0.1524)
				(type default)
			)
			(layer "F.SilkS")
		)
		(fp_line
			(start 3.550412 -1.050036)
			(end 3.550412 1.050036)
			(stroke
				(width 0.1524)
				(type default)
			)
			(layer "F.SilkS")
		)
		(fp_line
			(start -0.650494 1.050036)
			(end -0.650494 -1.050036)
			(stroke
				(width 0.1524)
				(type default)
			)
			(layer "F.SilkS")
		)
		(fp_line
			(start -0.650494 -1.050036)
			(end 3.550412 -1.050036)
			(stroke
				(width 0.1524)
				(type default)
			)
			(layer "F.SilkS")
		)
		(fp_poly
			(pts
				(xy 3.228086 -0.9652) (xy 3.228086 -1.100074) (xy -0.327914 -1.100074) (xy -0.327914 -0.9652) (xy -0.556514 -0.9652)
				(xy -0.556514 0.9652) (xy -0.327914 0.9652) (xy -0.327914 1.100074) (xy 3.228086 1.100074) (xy 3.228086 0.9652)
				(xy 3.456686 0.9652) (xy 3.456686 -0.9652)
			)
			(stroke
				(width 0)
				(type default)
			)
			(fill no)
			(layer "F.CrtYd")
		)
		(fp_text user "2"
			(at 4.256786 0.590804 0)
			(unlocked yes)
			(layer "F.SilkS")
			(effects
				(font
					(size 0.7874 0.5842)
					(thickness 0.1524)
				)
				(justify left)
			)
		)
		(fp_text user "1"
			(at -0.543814 1.632204 0)
			(unlocked yes)
			(layer "F.SilkS")
			(effects
				(font
					(size 0.7874 0.5842)
					(thickness 0.1524)
				)
				(justify left)
			)
		)
		(pad "1" smd rect
			(at 0 0 180)
			(size 1.016 1.8034)
			(layers "F.Cu" "F.Mask" "F.Paste")
			(net "P3V3_BLAD1")
		)
		(pad "2" smd rect
			(at 2.899918 0 180)
			(size 1.016 1.8034)
			(layers "F.Cu" "F.Mask" "F.Paste")
			(net "P3V3_10G_2_VCCT_L")
		)
	)
)
